# BASEBOARD_FAB2 (Tioga Pass) — schematic netlist excerpt (pin names and nets, part order shuffled) for the footprints in the layout excerpt that follows; sources: Cadence DE-HDL packaged netlist, KiCad conversion of Wiwynn_Tioga_Pass_MB.brd

J4A1  SCONN288_H44441004  SCONN  pkg PIP  page 53
  \12v\(1)  = P12V_NVDIMM_DEF
  VSS(93)  = GND
  DQ(4)  = M_F_DQ<5>
  VSS(92)  = GND
  DQ(0)  = M_F_DQ<1>
  VSS(91)  = GND
  DQS9P  = M_F_DQS_DP<9>
  DQS9N  = M_F_DQS_DN<9>
  VSS(90)  = GND
  DQ(6)  = M_F_DQ<7>
  VSS(89)  = GND
  DQ(2)  = M_F_DQ<3>
  VSS(88)  = GND
  DQ(12)  = M_F_DQ<13>
  VSS(87)  = GND
  DQ(8)  = M_F_DQ<9>
  VSS(86)  = GND
  DQS10P  = M_F_DQS_DP<10>
  DQS10N  = M_F_DQS_DN<10>
  VSS(85)  = GND
  DQ(14)  = M_F_DQ<15>
  VSS(84)  = GND
  DQ(10)  = M_F_DQ<11>
  VSS(83)  = GND
  DQ(20)  = M_F_DQ<21>
  VSS(82)  = GND
  DQ(16)  = M_F_DQ<17>
  VSS(81)  = GND
  DQS11P  = M_F_DQS_DP<11>
  DQS11N  = M_F_DQS_DN<11>
  VSS(80)  = GND
  DQ(22)  = M_F_DQ<23>
  VSS(79)  = GND
  DQ(18)  = M_F_DQ<19>
  VSS(78)  = GND
  DQ(28)  = M_F_DQ<29>
  VSS(77)  = GND
  DQ(24)  = M_F_DQ<25>
  VSS(76)  = GND
  DQS12P  = M_F_DQS_DP<12>
  DQS12N  = M_F_DQS_DN<12>
  VSS(75)  = GND
  DQ(30)  = M_F_DQ<31>
  VSS(74)  = GND
  DQ(26)  = M_F_DQ<27>
  VSS(73)  = GND
  CB(4)  = M_F_ECC<5>
  VSS(72)  = GND
  CB(0)  = M_F_ECC<1>
  VSS(71)  = GND
  DQS17P  = M_F_DQS_DP<17>
  DQS17N  = M_F_DQS_DN<17>
  VSS(70)  = GND
  CB(6)  = M_F_ECC<7>
  VSS(69)  = GND
  CB(2)  = M_F_ECC<3>
  VSS(68)  = GND
  RESET_N  = M_DEF_RST_N
  VDD(25)  = PVDDQ_DEF
  CKE(0)  = M_F_CKE<0>
  VDD(24)  = PVDDQ_DEF
  ACT_N  = M_F_ACT_N
  BG(0)  = M_F_BG<0>
  VDD(23)  = PVDDQ_DEF
  A12  = M_F_MA<12>
  A9  = M_F_MA<9>
  VDD(22)  = PVDDQ_DEF
  A8  = M_F_MA<8>
  A6  = M_F_MA<6>
  VDD(21)  = PVDDQ_DEF
  A3  = M_F_MA<3>
  A1  = M_F_MA<1>
  VDD(20)  = PVDDQ_DEF
  CK0P  = M_F_CLK_DP<0>
  CK0N  = M_F_CLK_DN<0>
  VDD(19)  = PVDDQ_DEF
  VTT(1)  = PVTT_DEF
  EVENT_N  = FM_DIMM_EVENT_COD_N
  A0  = M_F_MA<0>
  VDD(18)  = PVDDQ_DEF
  BA(0)  = M_F_BA<0>
  A16_RAS_N  = M_F_MA<16>
  VDD(17)  = PVDDQ_DEF
  S0_N  = M_F_CS_N<0>
  VDD(16)  = PVDDQ_DEF
  A15_CAS_N  = M_F_MA<15>
  ODT(0)  = M_F_ODT<0>
  VDD(15)  = PVDDQ_DEF
  S1_N  = M_F_CS_N<1>
  VDD(14)  = PVDDQ_DEF
  ODT(1)  = M_F_ODT<1>
  VDD(13)  = PVDDQ_DEF
  S2_N_C(0)  = M_F_CS_N<2>
  VSS(67)  = GND
  DQ(36)  = M_F_DQ<37>
  VSS(66)  = GND
  DQ(32)  = M_F_DQ<33>
  VSS(65)  = GND
  DQS13P  = M_F_DQS_DP<13>
  DQS13N  = M_F_DQS_DN<13>
  VSS(64)  = GND
  DQ(38)  = M_F_DQ<39>
  VSS(63)  = GND
  DQ(34)  = M_F_DQ<35>
  VSS(62)  = GND
  DQ(44)  = M_F_DQ<45>
  VSS(61)  = GND
  DQ(40)  = M_F_DQ<41>
  VSS(60)  = GND
  DQS14P  = M_F_DQS_DP<14>
  DQS14N  = M_F_DQS_DN<14>
  VSS(59)  = GND
  DQ(46)  = M_F_DQ<47>
  VSS(58)  = GND
  DQ(42)  = M_F_DQ<43>
  VSS(57)  = GND
  DQ(52)  = M_F_DQ<53>
  VSS(56)  = GND
  DQ(48)  = M_F_DQ<49>
  VSS(55)  = GND
  DQS15P  = M_F_DQS_DP<15>
  DQS15N  = M_F_DQS_DN<15>
  VSS(54)  = GND
  DQ(54)  = M_F_DQ<55>
  VSS(53)  = GND
  DQ(50)  = M_F_DQ<51>
  VSS(52)  = GND
  DQ(60)  = M_F_DQ<61>
  VSS(51)  = GND
  DQ(56)  = M_F_DQ<57>
  VSS(50)  = GND
  DQS16P  = M_F_DQS_DP<16>
  DQS16N  = M_F_DQS_DN<16>
  VSS(49)  = GND
  DQ(62)  = M_F_DQ<63>
  VSS(48)  = GND
  DQ(58)  = M_F_DQ<59>
  VSS(47)  = GND
  SA(0)  = GND
  SA(1)  = GND
  SCL  = SMB_DDR_DEF_VPP_SCL
  VPP(4)  = PVPP_DEF
  VPP(3)  = PVPP_DEF
  RFU(2)  = TP_CH_F_DIMM_F0_RFU_2
  \12v\(0)  = P12V_NVDIMM_DEF
  VREFCA  = M_F_VREF
  VSS(46)  = GND
  DQ(5)  = M_F_DQ<4>
  VSS(45)  = GND
  DQ(1)  = M_F_DQ<0>
  VSS(44)  = GND
  DQS0N  = M_F_DQS_DN<0>
  DQS0P  = M_F_DQS_DP<0>
  VSS(43)  = GND
  DQ(7)  = M_F_DQ<6>
  VSS(42)  = GND
  DQ(3)  = M_F_DQ<2>
  VSS(41)  = GND
  DQ(13)  = M_F_DQ<12>
  VSS(40)  = GND
  DQ(9)  = M_F_DQ<8>
  VSS(39)  = GND
  DQS1N  = M_F_DQS_DN<1>
  DQS1P  = M_F_DQS_DP<1>
  VSS(38)  = GND
  DQ(15)  = M_F_DQ<14>
  VSS(37)  = GND
  DQ(11)  = M_F_DQ<10>
  VSS(36)  = GND
  DQ(21)  = M_F_DQ<20>
  VSS(35)  = GND
  DQ(17)  = M_F_DQ<16>
  VSS(34)  = GND
  DQS2N  = M_F_DQS_DN<2>
  DQS2P  = M_F_DQS_DP<2>
  VSS(33)  = GND
  DQ(23)  = M_F_DQ<22>
  VSS(32)  = GND
  DQ(19)  = M_F_DQ<18>
  VSS(31)  = GND
  DQ(29)  = M_F_DQ<28>
  VSS(30)  = GND
  DQ(25)  = M_F_DQ<24>
  VSS(29)  = GND
  DQS3N  = M_F_DQS_DN<3>
  DQS3P  = M_F_DQS_DP<3>
  VSS(28)  = GND
  DQ(31)  = M_F_DQ<30>
  VSS(27)  = GND
  DQ(27)  = M_F_DQ<26>
  VSS(26)  = GND
  CB(5)  = M_F_ECC<4>
  VSS(25)  = GND
  CB(1)  = M_F_ECC<0>
  VSS(24)  = GND
  DQS8N  = M_F_DQS_DN<8>
  DQS8P  = M_F_DQS_DP<8>
  VSS(23)  = GND
  CB(7)  = M_F_ECC<6>
  VSS(22)  = GND
  CB(3)  = M_F_ECC<2>
  VSS(21)  = GND
  CKE(1)  = M_F_CKE<1>
  VDD(12)  = PVDDQ_DEF
  RFU(0)  = TP_CH_F_DIMM_F0_RFU_0
  VDD(11)  = PVDDQ_DEF
  BG(1)  = M_F_BG<1>
  ALERT_N  = M_F_ALERT_N
  VDD(10)  = PVDDQ_DEF
  A11  = M_F_MA<11>
  A7  = M_F_MA<7>
  VDD(9)  = PVDDQ_DEF
  A5  = M_F_MA<5>
  A4  = M_F_MA<4>
  VDD(8)  = PVDDQ_DEF
  A2  = M_F_MA<2>
  VDD(7)  = PVDDQ_DEF
  CK1P  = M_F_CLK_DP<1>
  CK1N  = M_F_CLK_DN<1>
  VDD(6)  = PVDDQ_DEF
  VTT(0)  = PVTT_DEF
  PAR  = M_F_PAR
  VDD(5)  = PVDDQ_DEF
  BA(1)  = M_F_BA<1>
  A10  = M_F_MA<10>
  VDD(4)  = PVDDQ_DEF
  RFU(1)  = TP_CH_F_DIMM_F0_RFU_1
  A14_WE_N  = M_F_MA<14>
  VDD(3)  = PVDDQ_DEF
  SAVE_N_NC  = FM_ADR_COMPLETE_DEF_N
  VDD(2)  = PVDDQ_DEF
  A13  = M_F_MA<13>
  VDD(1)  = PVDDQ_DEF
  A17  = M_F_MA<17>
  C(2)  = M_F_C<2>
  VDD(0)  = PVDDQ_DEF
  S3_N_C(1)  = M_F_CS_N<3>
  SA(2)  = PVPP_DEF
  VSS(20)  = GND
  DQ(37)  = M_F_DQ<36>
  VSS(19)  = GND
  DQ(33)  = M_F_DQ<32>
  VSS(18)  = GND
  DQS4N  = M_F_DQS_DN<4>
  DQS4P  = M_F_DQS_DP<4>
  VSS(17)  = GND
  DQ(39)  = M_F_DQ<38>
  VSS(16)  = GND
  DQ(35)  = M_F_DQ<34>
  VSS(15)  = GND
  DQ(45)  = M_F_DQ<44>
  VSS(14)  = GND
  DQ(41)  = M_F_DQ<40>
  VSS(13)  = GND
  DQS5N  = M_F_DQS_DN<5>
  DQS5P  = M_F_DQS_DP<5>
  VSS(12)  = GND
  DQ(47)  = M_F_DQ<46>
  VSS(11)  = GND
  DQ(43)  = M_F_DQ<42>
  VSS(10)  = GND
  DQ(53)  = M_F_DQ<52>
  VSS(9)  = GND
  DQ(49)  = M_F_DQ<48>
  VSS(8)  = GND
  DQS6N  = M_F_DQS_DN<6>
  DQS6P  = M_F_DQS_DP<6>
  VSS(7)  = GND
  DQ(55)  = M_F_DQ<54>
  VSS(6)  = GND
  DQ(51)  = M_F_DQ<50>
  VSS(5)  = GND
  DQ(61)  = M_F_DQ<60>
  VSS(4)  = GND
  DQ(57)  = M_F_DQ<56>
  VSS(3)  = GND
  DQS7N  = M_F_DQS_DN<7>
  DQS7P  = M_F_DQS_DP<7>
  VSS(2)  = GND
  DQ(63)  = M_F_DQ<62>
  VSS(1)  = GND
  DQ(59)  = M_F_DQ<58>
  VSS(0)  = GND
  VDDSPD  = PVPP_DEF
  SDA  = SMB_DDR_DEF_VPP_SDA
  VPP(1)  = PVPP_DEF
  VPP(0)  = PVPP_DEF
  VPP(2)  = PVPP_DEF

(kicad_pcb
	(version 20260206)
	(generator "pcbnew")
	(generator_version "10.0")
	(general
		(thickness 1.6)
		(legacy_teardrops no)
	)
	(paper "A4")
	(title_block
		(title "Wiwynn_Tioga_Pass_MB.brd")
		(comment 1 "Tioga Pass / footprint 431 of 4770 (J4A1), pads 252-291 of 291")
	)
	(layers
		(0 "F.Cu" signal "TOP")
		(4 "In1.Cu" signal "L2GND")
		(6 "In2.Cu" signal "L3")
		(8 "In3.Cu" signal "L4GND")
		(10 "In4.Cu" signal "L5")
		(12 "In5.Cu" signal "L6GND")
		(14 "In6.Cu" signal "L7VCC")
		(16 "In7.Cu" signal "L8VCC")
		(18 "In8.Cu" signal "L9GND")
		(20 "In9.Cu" signal "L10")
		(22 "In10.Cu" signal "L11GND")
		(24 "In11.Cu" signal "L12")
		(26 "In12.Cu" signal "L13GND")
		(2 "B.Cu" signal "BOTTOM")
		(9 "F.Adhes" user "F.Adhesive")
		(11 "B.Adhes" user "B.Adhesive")
		(13 "F.Paste" user "Package Geometry/Pastemask Top")
		(15 "B.Paste" user "Package Geometry/Pastemask Bottom")
		(5 "F.SilkS" user "Ref Des/Silkscreen Top")
		(7 "B.SilkS" user "Ref Des/Silkscreen Bottom")
		(1 "F.Mask" user "Board Geometry/Soldermask Top")
		(3 "B.Mask" user "Board Geometry/Soldermask Bottom")
		(17 "Dwgs.User" user "User.Drawings")
		(19 "Cmts.User" user "User.Comments")
		(21 "Eco1.User" user "User.Eco1")
		(23 "Eco2.User" user "User.Eco2")
		(25 "Edge.Cuts" user "Board Geometry/Outline")
		(27 "Margin" user)
		(31 "F.CrtYd" user "Package Geometry/Place Bound Top")
		(29 "B.CrtYd" user "Package Geometry/Place Bound Bottom")
		(35 "F.Fab" user "Ref Des/Assembly Top")
		(33 "B.Fab" user "Ref Des/Assembly Bottom")
	)
	(footprint ""
		(layer "F.Cu")
		(at 194.700398 -152.273 90)
		(property "Reference" "J4A1"
			(at -2.699512 42.53611 0)
			(unlocked yes)
			(layer "F.SilkS")
			(effects
				(font
					(size 0.7874 0.5842)
					(thickness 0.1524)
				)
				(justify left)
			)
		)
		(property "Value" ""
			(at 0 0 90)
			(layer "F.Fab")
			(effects
				(font
					(size 1.27 1.27)
				)
			)
		)
		(duplicate_pad_numbers_are_jumpers no)
		(pad "249" smd rect
			(at 4.59994 93.49994 90)
			(size 1.8034 0.508)
			(layers "F.Cu" "F.Mask" "F.Paste")
			(net "M_F_DQ<34>")
		)
		(pad "250" smd rect
			(at 4.59994 94.350078 90)
			(size 1.8034 0.508)
			(layers "F.Cu" "F.Mask" "F.Paste")
			(net "GND")
		)
		(pad "251" smd rect
			(at 4.59994 95.199962 90)
			(size 1.8034 0.508)
			(layers "F.Cu" "F.Mask" "F.Paste")
			(net "M_F_DQ<44>")
		)
		(pad "252" smd rect
			(at 4.59994 96.0501 90)
			(size 1.8034 0.508)
			(layers "F.Cu" "F.Mask" "F.Paste")
			(net "GND")
		)
		(pad "253" smd rect
			(at 4.59994 96.899984 90)
			(size 1.8034 0.508)
			(layers "F.Cu" "F.Mask" "F.Paste")
			(net "M_F_DQ<40>")
		)
		(pad "254" smd rect
			(at 4.59994 97.750122 90)
			(size 1.8034 0.508)
			(layers "F.Cu" "F.Mask" "F.Paste")
			(net "GND")
		)
		(pad "255" smd rect
			(at 4.59994 98.600006 90)
			(size 1.8034 0.508)
			(layers "F.Cu" "F.Mask" "F.Paste")
			(net "M_F_DQS_DN<5>")
		)
		(pad "256" smd rect
			(at 4.59994 99.44989 90)
			(size 1.8034 0.508)
			(layers "F.Cu" "F.Mask" "F.Paste")
			(net "M_F_DQS_DP<5>")
		)
		(pad "257" smd rect
			(at 4.59994 100.300028 90)
			(size 1.8034 0.508)
			(layers "F.Cu" "F.Mask" "F.Paste")
			(net "GND")
		)
		(pad "258" smd rect
			(at 4.59994 101.149912 90)
			(size 1.8034 0.508)
			(layers "F.Cu" "F.Mask" "F.Paste")
			(net "M_F_DQ<46>")
		)
		(pad "259" smd rect
			(at 4.59994 102.00005 90)
			(size 1.8034 0.508)
			(layers "F.Cu" "F.Mask" "F.Paste")
			(net "GND")
		)
		(pad "260" smd rect
			(at 4.59994 102.849934 90)
			(size 1.8034 0.508)
			(layers "F.Cu" "F.Mask" "F.Paste")
			(net "M_F_DQ<42>")
		)
		(pad "261" smd rect
			(at 4.59994 103.700072 90)
			(size 1.8034 0.508)
			(layers "F.Cu" "F.Mask" "F.Paste")
			(net "GND")
		)
		(pad "262" smd rect
			(at 4.59994 104.549956 90)
			(size 1.8034 0.508)
			(layers "F.Cu" "F.Mask" "F.Paste")
			(net "M_F_DQ<52>")
		)
		(pad "263" smd rect
			(at 4.59994 105.400094 90)
			(size 1.8034 0.508)
			(layers "F.Cu" "F.Mask" "F.Paste")
			(net "GND")
		)
		(pad "264" smd rect
			(at 4.59994 106.249978 90)
			(size 1.8034 0.508)
			(layers "F.Cu" "F.Mask" "F.Paste")
			(net "M_F_DQ<48>")
		)
		(pad "265" smd rect
			(at 4.59994 107.100116 90)
			(size 1.8034 0.508)
			(layers "F.Cu" "F.Mask" "F.Paste")
			(net "GND")
		)
		(pad "266" smd rect
			(at 4.59994 107.95 90)
			(size 1.8034 0.508)
			(layers "F.Cu" "F.Mask" "F.Paste")
			(net "M_F_DQS_DN<6>")
		)
		(pad "267" smd rect
			(at 4.59994 108.799884 90)
			(size 1.8034 0.508)
			(layers "F.Cu" "F.Mask" "F.Paste")
			(net "M_F_DQS_DP<6>")
		)
		(pad "268" smd rect
			(at 4.59994 109.650022 90)
			(size 1.8034 0.508)
			(layers "F.Cu" "F.Mask" "F.Paste")
			(net "GND")
		)
		(pad "269" smd rect
			(at 4.59994 110.499906 90)
			(size 1.8034 0.508)
			(layers "F.Cu" "F.Mask" "F.Paste")
			(net "M_F_DQ<54>")
		)
		(pad "270" smd rect
			(at 4.59994 111.350044 90)
			(size 1.8034 0.508)
			(layers "F.Cu" "F.Mask" "F.Paste")
			(net "GND")
		)
		(pad "271" smd rect
			(at 4.59994 112.199928 90)
			(size 1.8034 0.508)
			(layers "F.Cu" "F.Mask" "F.Paste")
			(net "M_F_DQ<50>")
		)
		(pad "272" smd rect
			(at 4.59994 113.050066 90)
			(size 1.8034 0.508)
			(layers "F.Cu" "F.Mask" "F.Paste")
			(net "GND")
		)
		(pad "273" smd rect
			(at 4.59994 113.89995 90)
			(size 1.8034 0.508)
			(layers "F.Cu" "F.Mask" "F.Paste")
			(net "M_F_DQ<60>")
		)
		(pad "274" smd rect
			(at 4.59994 114.750088 90)
			(size 1.8034 0.508)
			(layers "F.Cu" "F.Mask" "F.Paste")
			(net "GND")
		)
		(pad "275" smd rect
			(at 4.59994 115.599972 90)
			(size 1.8034 0.508)
			(layers "F.Cu" "F.Mask" "F.Paste")
			(net "M_F_DQ<56>")
		)
		(pad "276" smd rect
			(at 4.59994 116.45011 90)
			(size 1.8034 0.508)
			(layers "F.Cu" "F.Mask" "F.Paste")
			(net "GND")
		)
		(pad "277" smd rect
			(at 4.59994 117.299994 90)
			(size 1.8034 0.508)
			(layers "F.Cu" "F.Mask" "F.Paste")
			(net "M_F_DQS_DN<7>")
		)
		(pad "278" smd rect
			(at 4.59994 118.149878 90)
			(size 1.8034 0.508)
			(layers "F.Cu" "F.Mask" "F.Paste")
			(net "M_F_DQS_DP<7>")
		)
		(pad "279" smd rect
			(at 4.59994 119.000016 90)
			(size 1.8034 0.508)
			(layers "F.Cu" "F.Mask" "F.Paste")
			(net "GND")
		)
		(pad "280" smd rect
			(at 4.59994 119.8499 90)
			(size 1.8034 0.508)
			(layers "F.Cu" "F.Mask" "F.Paste")
			(net "M_F_DQ<62>")
		)
		(pad "281" smd rect
			(at 4.59994 120.700038 90)
			(size 1.8034 0.508)
			(layers "F.Cu" "F.Mask" "F.Paste")
			(net "GND")
		)
		(pad "282" smd rect
			(at 4.59994 121.549922 90)
			(size 1.8034 0.508)
			(layers "F.Cu" "F.Mask" "F.Paste")
			(net "M_F_DQ<58>")
		)
		(pad "283" smd rect
			(at 4.59994 122.40006 90)
			(size 1.8034 0.508)
			(layers "F.Cu" "F.Mask" "F.Paste")
			(net "GND")
		)
		(pad "284" smd rect
			(at 4.59994 123.249944 90)
			(size 1.8034 0.508)
			(layers "F.Cu" "F.Mask" "F.Paste")
			(net "PVPP_DEF")
		)
		(pad "285" smd rect
			(at 4.59994 124.100082 90)
			(size 1.8034 0.508)
			(layers "F.Cu" "F.Mask" "F.Paste")
			(net "SMB_DDR_DEF_VPP_SDA")
		)
		(pad "286" smd rect
			(at 4.59994 124.949966 90)
			(size 1.8034 0.508)
			(layers "F.Cu" "F.Mask" "F.Paste")
			(net "PVPP_DEF")
		)
		(pad "287" smd rect
			(at 4.59994 125.800104 90)
			(size 1.8034 0.508)
			(layers "F.Cu" "F.Mask" "F.Paste")
			(net "PVPP_DEF")
		)
		(pad "288" smd rect
			(at 4.59994 126.649988 90)
			(size 1.8034 0.508)
			(layers "F.Cu" "F.Mask" "F.Paste")
			(net "PVPP_DEF")
		)
	)
)
